# TIMECARD (Time Appliance Project (Time Card)) — schematic netlist excerpt (pin names and nets, part order shuffled) for the footprints in the layout excerpt that follows; sources: Cadence DE-HDL packaged netlist, KiCad conversion of R4006-B0001-02_R01.brd

R221  RESISTOR  100OHM 1%  pkg SMC_0402R_H016  page 10 : \1\ = XP3R3V_FPGA ; \2\ = FPGA_M2
R392  RESISTOR  33OHM 1%  pkg SMC_0402R_H016  page 26 : \1\ = SMA3_LED_GREEN_N ; \2\ = UNNAMED_14_LED4PV14_I267_4

(kicad_pcb
	(version 20260206)
	(generator "pcbnew")
	(generator_version "10.0")
	(general
		(thickness 1.6)
		(legacy_teardrops no)
	)
	(paper "A4")
	(title_block
		(title "timecard-production-celestica-r4006 — R4006-B0001-02_R01.brd")
		(comment 1 "Time Appliance Project (Time Card) / footprints 370-371 of 1113")
	)
	(layers
		(0 "F.Cu" signal "TOP")
		(4 "In1.Cu" signal "L02_GND1")
		(6 "In2.Cu" signal "L03_SIG1")
		(8 "In3.Cu" signal "L04_GND2")
		(10 "In4.Cu" signal "L05_VCC1")
		(12 "In5.Cu" signal "L06_VCC2")
		(14 "In6.Cu" signal "L07_GND3")
		(16 "In7.Cu" signal "L08_SIG2")
		(18 "In8.Cu" signal "L09_GND4")
		(2 "B.Cu" signal "BOTTOM")
		(9 "F.Adhes" user "F.Adhesive")
		(11 "B.Adhes" user "B.Adhesive")
		(13 "F.Paste" user "Package Geometry/Pastemask Top")
		(15 "B.Paste" user "Package Geometry/Pastemask Bottom")
		(5 "F.SilkS" user "Ref Des/Silkscreen Top")
		(7 "B.SilkS" user "Ref Des/Silkscreen Bottom")
		(1 "F.Mask" user "Board Geometry/Soldermask Top")
		(3 "B.Mask" user "Board Geometry/Soldermask Bottom")
		(17 "Dwgs.User" user "User.Drawings")
		(19 "Cmts.User" user "User.Comments")
		(21 "Eco1.User" user "User.Eco1")
		(23 "Eco2.User" user "User.Eco2")
		(25 "Edge.Cuts" user "Board Geometry/Outline")
		(27 "Margin" user)
		(31 "F.CrtYd" user "Package Geometry/Place Bound Top")
		(29 "B.CrtYd" user "Package Geometry/Place Bound Bottom")
		(35 "F.Fab" user "Ref Des/Assembly Top")
		(33 "B.Fab" user "Ref Des/Assembly Bottom")
	)
	(footprint ""
		(layer "F.Cu")
		(at 9.5758 -68.201032 90)
		(property "Reference" "R392"
			(at 3.553968 -0.64643 90)
			(unlocked yes)
			(layer "F.SilkS")
			(effects
				(font
					(size 0.7874 0.5842)
					(thickness 0.1524)
				)
			)
		)
		(property "Value" "VAL*"
			(at 0.02032 2.13233 90)
			(unlocked yes)
			(layer "F.Fab")
			(hide yes)
			(effects
				(font
					(size 0.7874 0.5842)
					(thickness 0.1524)
				)
			)
		)
		(property "Tolerance" "TOL*"
			(at 0.044704 3.05435 90)
			(unlocked yes)
			(layer "Cmts.User")
			(hide yes)
			(effects
				(font
					(size 0.7874 0.5842)
					(thickness 0.1524)
				)
			)
		)
		(property "User Part Number" "PARTNUM*"
			(at 0.02032 4.024884 90)
			(unlocked yes)
			(layer "Cmts.User")
			(hide yes)
			(effects
				(font
					(size 0.7874 0.5842)
					(thickness 0.1524)
				)
			)
		)
		(property "Device Type" "RESISTOR-G155-133R0-01,33OHM,1%"
			(at 0.008382 1.210564 90)
			(unlocked yes)
			(layer "F.Fab")
			(hide yes)
			(effects
				(font
					(size 0.7874 0.5842)
					(thickness 0.1524)
				)
			)
		)
		(duplicate_pad_numbers_are_jumpers no)
		(fp_line
			(start 1.143 -0.5588)
			(end -1.143 -0.5588)
			(stroke
				(width 0.1)
				(type default)
			)
			(layer "F.SilkS")
		)
		(fp_line
			(start -1.143 -0.5588)
			(end -1.143 0.5588)
			(stroke
				(width 0.1)
				(type default)
			)
			(layer "F.SilkS")
		)
		(fp_line
			(start 1.143 0.5588)
			(end 1.143 -0.5588)
			(stroke
				(width 0.1)
				(type default)
			)
			(layer "F.SilkS")
		)
		(fp_line
			(start -1.143 0.5588)
			(end 1.143 0.5588)
			(stroke
				(width 0.1)
				(type default)
			)
			(layer "F.SilkS")
		)
		(fp_rect
			(start -1.143 -0.5588)
			(end 1.143 0.5588)
			(stroke
				(width 0)
				(type default)
			)
			(fill no)
			(layer "F.CrtYd")
		)
		(fp_line
			(start 0.508 -0.3048)
			(end -0.508 -0.3048)
			(stroke
				(width 0.1)
				(type default)
			)
			(layer "F.Fab")
		)
		(fp_line
			(start -0.508 -0.3048)
			(end -0.508 0.3048)
			(stroke
				(width 0.1)
				(type default)
			)
			(layer "F.Fab")
		)
		(fp_line
			(start 0.508 0.3048)
			(end 0.508 -0.3048)
			(stroke
				(width 0.1)
				(type default)
			)
			(layer "F.Fab")
		)
		(fp_line
			(start -0.508 0.3048)
			(end 0.508 0.3048)
			(stroke
				(width 0.1)
				(type default)
			)
			(layer "F.Fab")
		)
		(pad "1" smd rect
			(at -0.5334 0 90)
			(size 0.7112 0.6096)
			(layers "F.Cu" "F.Mask" "F.Paste")
			(net "SMA3_LED_GREEN_N")
		)
		(pad "2" smd rect
			(at 0.5334 0 90)
			(size 0.7112 0.6096)
			(layers "F.Cu" "F.Mask" "F.Paste")
			(net "UNNAMED_14_LED4PV14_I267_4")
		)
		(zone
			(layer "F.Cu")
			(hatch none 0.5)
			(connect_pads
				(clearance 0)
			)
			(min_thickness 0.25)
			(keepout
				(tracks not_allowed)
				(vias allowed)
				(pads allowed)
				(copperpour not_allowed)
				(footprints allowed)
			)
			(placement
				(enabled no)
				(sheetname "")
			)
			(fill
				(thermal_gap 0.5)
				(thermal_bridge_width 0.5)
				(island_removal_mode 0)
			)
			(polygon
				(pts
					(xy 9.271 -68.124832) (xy 9.8806 -68.124832) (xy 9.8806 -68.277232) (xy 9.271 -68.277232)
				)
			)
		)
		(zone
			(layer "F.Cu")
			(hatch none 0.5)
			(connect_pads
				(clearance 0)
			)
			(min_thickness 0.25)
			(keepout
				(tracks allowed)
				(vias not_allowed)
				(pads allowed)
				(copperpour not_allowed)
				(footprints allowed)
			)
			(placement
				(enabled no)
				(sheetname "")
			)
			(fill
				(thermal_gap 0.5)
				(thermal_bridge_width 0.5)
				(island_removal_mode 0)
			)
			(polygon
				(pts
					(xy 9.271 -68.124832) (xy 9.8806 -68.124832) (xy 9.8806 -68.277232) (xy 9.271 -68.277232)
				)
			)
		)
	)
	(footprint ""
		(layer "F.Cu")
		(at 126.492 -35.179 180)
		(property "Reference" "R221"
			(at -2.921 -1.56337 0)
			(unlocked yes)
			(layer "F.SilkS")
			(effects
				(font
					(size 0.7874 0.5842)
					(thickness 0.1524)
				)
			)
		)
		(property "Value" "VAL*"
			(at 0.02032 2.13233 180)
			(unlocked yes)
			(layer "F.Fab")
			(hide yes)
			(effects
				(font
					(size 0.7874 0.5842)
					(thickness 0.1524)
				)
			)
		)
		(property "Device Type" "RESISTOR-G155-11000-01,100OHM,A"
			(at 0.008382 1.210564 180)
			(unlocked yes)
			(layer "F.Fab")
			(hide yes)
			(effects
				(font
					(size 0.7874 0.5842)
					(thickness 0.1524)
				)
			)
		)
		(property "User Part Number" "PARTNUM*"
			(at 0.02032 4.024884 180)
			(unlocked yes)
			(layer "Cmts.User")
			(hide yes)
			(effects
				(font
					(size 0.7874 0.5842)
					(thickness 0.1524)
				)
			)
		)
		(property "Tolerance" "TOL*"
			(at 0.044704 3.05435 180)
			(unlocked yes)
			(layer "Cmts.User")
			(hide yes)
			(effects
				(font
					(size 0.7874 0.5842)
					(thickness 0.1524)
				)
			)
		)
		(duplicate_pad_numbers_are_jumpers no)
		(fp_line
			(start 1.143 0.5588)
			(end 1.143 -0.5588)
			(stroke
				(width 0.1)
				(type default)
			)
			(layer "F.SilkS")
		)
		(fp_line
			(start 1.143 -0.5588)
			(end -1.143 -0.5588)
			(stroke
				(width 0.1)
				(type default)
			)
			(layer "F.SilkS")
		)
		(fp_line
			(start -1.143 0.5588)
			(end 1.143 0.5588)
			(stroke
				(width 0.1)
				(type default)
			)
			(layer "F.SilkS")
		)
		(fp_line
			(start -1.143 -0.5588)
			(end -1.143 0.5588)
			(stroke
				(width 0.1)
				(type default)
			)
			(layer "F.SilkS")
		)
		(fp_rect
			(start 1.143 0.5588)
			(end -1.143 -0.5588)
			(stroke
				(width 0)
				(type default)
			)
			(fill no)
			(layer "F.CrtYd")
		)
		(fp_line
			(start 0.508 0.3048)
			(end 0.508 -0.3048)
			(stroke
				(width 0.1)
				(type default)
			)
			(layer "F.Fab")
		)
		(fp_line
			(start 0.508 -0.3048)
			(end -0.508 -0.3048)
			(stroke
				(width 0.1)
				(type default)
			)
			(layer "F.Fab")
		)
		(fp_line
			(start -0.508 0.3048)
			(end 0.508 0.3048)
			(stroke
				(width 0.1)
				(type default)
			)
			(layer "F.Fab")
		)
		(fp_line
			(start -0.508 -0.3048)
			(end -0.508 0.3048)
			(stroke
				(width 0.1)
				(type default)
			)
			(layer "F.Fab")
		)
		(pad "1" smd rect
			(at -0.5334 0 180)
			(size 0.7112 0.6096)
			(layers "F.Cu" "F.Mask" "F.Paste")
			(net "XP3R3V_FPGA")
		)
		(pad "2" smd rect
			(at 0.5334 0 180)
			(size 0.7112 0.6096)
			(layers "F.Cu" "F.Mask" "F.Paste")
			(net "FPGA_M2")
		)
		(zone
			(layer "F.Cu")
			(hatch none 0.5)
			(connect_pads
				(clearance 0)
			)
			(min_thickness 0.25)
			(keepout
				(tracks allowed)
				(vias not_allowed)
				(pads allowed)
				(copperpour not_allowed)
				(footprints allowed)
			)
			(placement
				(enabled no)
				(sheetname "")
			)
			(fill
				(thermal_gap 0.5)
				(thermal_bridge_width 0.5)
				(island_removal_mode 0)
			)
			(polygon
				(pts
					(xy 126.4158 -35.4838) (xy 126.4158 -34.8742) (xy 126.5682 -34.8742) (xy 126.5682 -35.4838)
				)
			)
		)
	)
)
